# BASEBOARD_FAB2 (Tioga Pass) — schematic netlist excerpt (pin names and nets, part order shuffled) for the footprints in the layout excerpt that follows; sources: Cadence DE-HDL packaged netlist, KiCad conversion of Wiwynn_Tioga_Pass_MB.brd

C6G4  CAP  10UF 4V 20% X6S  pkg 0603LF  page 231 : A = PVPP_ABC ; B = GND
R25W127  RES  150.0 1% CHIP  pkg 0402  page 252 : A = V_IO_G_J ; B = GND
C3G7  CAP  10UF 4V 20% X6S  pkg 0603LF  page 233 : A = PVPP_GHJ ; B = GND

(kicad_pcb
	(version 20260206)
	(generator "pcbnew")
	(generator_version "10.0")
	(general
		(thickness 1.6)
		(legacy_teardrops no)
	)
	(paper "A4")
	(title_block
		(title "Wiwynn_Tioga_Pass_MB.brd")
		(comment 1 "Tioga Pass / footprints 1545-1547 of 4770")
	)
	(layers
		(0 "F.Cu" signal "TOP")
		(4 "In1.Cu" signal "L2GND")
		(6 "In2.Cu" signal "L3")
		(8 "In3.Cu" signal "L4GND")
		(10 "In4.Cu" signal "L5")
		(12 "In5.Cu" signal "L6GND")
		(14 "In6.Cu" signal "L7VCC")
		(16 "In7.Cu" signal "L8VCC")
		(18 "In8.Cu" signal "L9GND")
		(20 "In9.Cu" signal "L10")
		(22 "In10.Cu" signal "L11GND")
		(24 "In11.Cu" signal "L12")
		(26 "In12.Cu" signal "L13GND")
		(2 "B.Cu" signal "BOTTOM")
		(9 "F.Adhes" user "F.Adhesive")
		(11 "B.Adhes" user "B.Adhesive")
		(13 "F.Paste" user "Package Geometry/Pastemask Top")
		(15 "B.Paste" user "Package Geometry/Pastemask Bottom")
		(5 "F.SilkS" user "Ref Des/Silkscreen Top")
		(7 "B.SilkS" user "Ref Des/Silkscreen Bottom")
		(1 "F.Mask" user "Board Geometry/Soldermask Top")
		(3 "B.Mask" user "Board Geometry/Soldermask Bottom")
		(17 "Dwgs.User" user "User.Drawings")
		(19 "Cmts.User" user "User.Comments")
		(21 "Eco1.User" user "User.Eco1")
		(23 "Eco2.User" user "User.Eco2")
		(25 "Edge.Cuts" user "Board Geometry/Outline")
		(27 "Margin" user)
		(31 "F.CrtYd" user "Package Geometry/Place Bound Top")
		(29 "B.CrtYd" user "Package Geometry/Place Bound Bottom")
		(35 "F.Fab" user "Ref Des/Assembly Top")
		(33 "B.Fab" user "Ref Des/Assembly Bottom")
	)
	(footprint ""
		(layer "F.Cu")
		(at 489.0262 -34.8742 -90)
		(property "Reference" "R25W127"
			(at -0.8382 -0.67818 270)
			(unlocked yes)
			(layer "F.SilkS")
			(effects
				(font
					(size 0.4064 0.254)
					(thickness 0.1524)
				)
				(justify left)
			)
		)
		(property "Value" ""
			(at 0 0 270)
			(layer "F.Fab")
			(effects
				(font
					(size 1.27 1.27)
				)
			)
		)
		(duplicate_pad_numbers_are_jumpers no)
		(fp_poly
			(pts
				(xy -0.2794 -0.1016) (xy 0.2794 -0.1016) (xy 0.2794 0.9906) (xy -0.2794 0.9906)
			)
			(stroke
				(width 0)
				(type default)
			)
			(fill no)
			(layer "F.CrtYd")
		)
		(fp_line
			(start -0.2794 0.9906)
			(end 0.2794 0.9906)
			(stroke
				(width 0.1)
				(type default)
			)
			(layer "F.Fab")
		)
		(fp_line
			(start 0.2794 0.9906)
			(end 0.2794 -0.1016)
			(stroke
				(width 0.1)
				(type default)
			)
			(layer "F.Fab")
		)
		(fp_line
			(start -0.2794 -0.1016)
			(end -0.2794 0.9906)
			(stroke
				(width 0.1)
				(type default)
			)
			(layer "F.Fab")
		)
		(fp_line
			(start 0.2794 -0.1016)
			(end -0.2794 -0.1016)
			(stroke
				(width 0.1)
				(type default)
			)
			(layer "F.Fab")
		)
		(pad "1" smd rect
			(at 0 0 270)
			(size 0.508 0.508)
			(layers "F.Cu" "F.Mask" "F.Paste")
			(net "V_IO_G_J")
		)
		(pad "2" smd rect
			(at 0 0.889 270)
			(size 0.508 0.508)
			(layers "F.Cu" "F.Mask" "F.Paste")
			(net "GND")
		)
		(zone
			(layer "F.Cu")
			(hatch none 0.5)
			(connect_pads
				(clearance 0)
			)
			(min_thickness 0.25)
			(keepout
				(tracks not_allowed)
				(vias allowed)
				(pads allowed)
				(copperpour not_allowed)
				(footprints allowed)
			)
			(placement
				(enabled no)
				(sheetname "")
			)
			(fill
				(thermal_gap 0.5)
				(thermal_bridge_width 0.5)
				(island_removal_mode 0)
			)
			(polygon
				(pts
					(xy 488.3912 -35.1282) (xy 488.3912 -34.6202) (xy 488.7722 -34.6202) (xy 488.7722 -35.1282)
				)
			)
		)
		(zone
			(layer "F.Cu")
			(hatch none 0.5)
			(connect_pads
				(clearance 0)
			)
			(min_thickness 0.25)
			(keepout
				(tracks allowed)
				(vias not_allowed)
				(pads allowed)
				(copperpour not_allowed)
				(footprints allowed)
			)
			(placement
				(enabled no)
				(sheetname "")
			)
			(fill
				(thermal_gap 0.5)
				(thermal_bridge_width 0.5)
				(island_removal_mode 0)
			)
			(polygon
				(pts
					(xy 488.7722 -35.1282) (xy 488.7722 -34.6202) (xy 488.3912 -34.6202) (xy 488.3912 -35.1282)
				)
			)
		)
	)
	(footprint ""
		(layer "F.Cu")
		(at 318.543432 -3.302 -90)
		(property "Reference" "C6G4"
			(at 0 0 270)
			(layer "F.SilkS")
			(hide yes)
			(effects
				(font
					(size 1.27 1.27)
				)
			)
		)
		(property "Value" ""
			(at 0 0 270)
			(layer "F.Fab")
			(effects
				(font
					(size 1.27 1.27)
				)
			)
		)
		(duplicate_pad_numbers_are_jumpers no)
		(fp_poly
			(pts
				(xy -0.4953 -0.2032) (xy 0.4953 -0.2032) (xy 0.4953 1.6002) (xy -0.4953 1.6002)
			)
			(stroke
				(width 0)
				(type default)
			)
			(fill no)
			(layer "F.CrtYd")
		)
		(fp_line
			(start -0.4953 1.6002)
			(end -0.4953 -0.2032)
			(stroke
				(width 0.1)
				(type default)
			)
			(layer "F.Fab")
		)
		(fp_line
			(start 0.4953 1.6002)
			(end -0.4953 1.6002)
			(stroke
				(width 0.1)
				(type default)
			)
			(layer "F.Fab")
		)
		(fp_line
			(start -0.4953 -0.2032)
			(end 0.4953 -0.2032)
			(stroke
				(width 0.1)
				(type default)
			)
			(layer "F.Fab")
		)
		(fp_line
			(start 0.4953 -0.2032)
			(end 0.4953 1.6002)
			(stroke
				(width 0.1)
				(type default)
			)
			(layer "F.Fab")
		)
		(pad "1" smd rect
			(at 0 0 270)
			(size 0.762 0.889)
			(layers "F.Cu" "F.Mask" "F.Paste")
			(net "PVPP_ABC")
		)
		(pad "2" smd rect
			(at 0 1.397 270)
			(size 0.762 0.889)
			(layers "F.Cu" "F.Mask" "F.Paste")
			(net "GND")
		)
		(zone
			(layer "F.Cu")
			(hatch none 0.5)
			(connect_pads
				(clearance 0)
			)
			(min_thickness 0.25)
			(keepout
				(tracks not_allowed)
				(vias allowed)
				(pads allowed)
				(copperpour not_allowed)
				(footprints allowed)
			)
			(placement
				(enabled no)
				(sheetname "")
			)
			(fill
				(thermal_gap 0.5)
				(thermal_bridge_width 0.5)
				(island_removal_mode 0)
			)
			(polygon
				(pts
					(xy 318.098932 -3.683) (xy 318.098932 -2.921) (xy 317.590932 -2.921) (xy 317.590932 -3.683)
				)
			)
		)
	)
	(footprint ""
		(layer "F.Cu")
		(at 153.543 -3.302 -90)
		(property "Reference" "C3G7"
			(at 0 0 270)
			(layer "F.SilkS")
			(hide yes)
			(effects
				(font
					(size 1.27 1.27)
				)
			)
		)
		(property "Value" ""
			(at 0 0 270)
			(layer "F.Fab")
			(effects
				(font
					(size 1.27 1.27)
				)
			)
		)
		(duplicate_pad_numbers_are_jumpers no)
		(fp_poly
			(pts
				(xy -0.4953 -0.2032) (xy 0.4953 -0.2032) (xy 0.4953 1.6002) (xy -0.4953 1.6002)
			)
			(stroke
				(width 0)
				(type default)
			)
			(fill no)
			(layer "F.CrtYd")
		)
		(fp_line
			(start -0.4953 1.6002)
			(end -0.4953 -0.2032)
			(stroke
				(width 0.1)
				(type default)
			)
			(layer "F.Fab")
		)
		(fp_line
			(start 0.4953 1.6002)
			(end -0.4953 1.6002)
			(stroke
				(width 0.1)
				(type default)
			)
			(layer "F.Fab")
		)
		(fp_line
			(start -0.4953 -0.2032)
			(end 0.4953 -0.2032)
			(stroke
				(width 0.1)
				(type default)
			)
			(layer "F.Fab")
		)
		(fp_line
			(start 0.4953 -0.2032)
			(end 0.4953 1.6002)
			(stroke
				(width 0.1)
				(type default)
			)
			(layer "F.Fab")
		)
		(pad "1" smd rect
			(at 0 0 270)
			(size 0.762 0.889)
			(layers "F.Cu" "F.Mask" "F.Paste")
			(net "PVPP_GHJ")
		)
		(pad "2" smd rect
			(at 0 1.397 270)
			(size 0.762 0.889)
			(layers "F.Cu" "F.Mask" "F.Paste")
			(net "GND")
		)
		(zone
			(layer "F.Cu")
			(hatch none 0.5)
			(connect_pads
				(clearance 0)
			)
			(min_thickness 0.25)
			(keepout
				(tracks not_allowed)
				(vias allowed)
				(pads allowed)
				(copperpour not_allowed)
				(footprints allowed)
			)
			(placement
				(enabled no)
				(sheetname "")
			)
			(fill
				(thermal_gap 0.5)
				(thermal_bridge_width 0.5)
				(island_removal_mode 0)
			)
			(polygon
				(pts
					(xy 153.0985 -3.683) (xy 153.0985 -2.921) (xy 152.5905 -2.921) (xy 152.5905 -3.683)
				)
			)
		)
	)
)
